(kicad_pcb
	(version 20260206)
	(generator "pcbnew")
	(generator_version "10.0")
	(general
		(thickness 1.6)
		(legacy_teardrops no)
	)
	(paper "A4")
	(title_block
		(title "01162023_DA0F0TEBIF0_F0T_Expander_BD_F_brd_V02_OCP.brd")
		(comment 1 "Grand Teton / footprint 5622 of 9728 (PEX2), pads 957-1074 of 2397")
	)
	(layers
		(0 "F.Cu" signal "TOP")
		(4 "In1.Cu" signal "GND")
		(6 "In2.Cu" signal "VCC")
		(8 "In3.Cu" signal "VCC1")
		(10 "In4.Cu" signal "GND1")
		(12 "In5.Cu" signal "IN1")
		(14 "In6.Cu" signal "GND2")
		(16 "In7.Cu" signal "IN2")
		(18 "In8.Cu" signal "GND3")
		(20 "In9.Cu" signal "IN3")
		(22 "In10.Cu" signal "GND4")
		(24 "In11.Cu" signal "IN4")
		(26 "In12.Cu" signal "GND5")
		(28 "In13.Cu" signal "IN5")
		(30 "In14.Cu" signal "GND6")
		(32 "In15.Cu" signal "IN6")
		(34 "In16.Cu" signal "GND7")
		(2 "B.Cu" signal "BOTTOM")
		(9 "F.Adhes" user "F.Adhesive")
		(11 "B.Adhes" user "B.Adhesive")
		(13 "F.Paste" user "Package Geometry/Pastemask Top")
		(15 "B.Paste" user "Package Geometry/Pastemask Bottom")
		(5 "F.SilkS" user "Ref Des/Silkscreen Top")
		(7 "B.SilkS" user "Ref Des/Silkscreen Bottom")
		(1 "F.Mask" user "Board Geometry/Soldermask Top")
		(3 "B.Mask" user "Board Geometry/Soldermask Bottom")
		(17 "Dwgs.User" user "User.Drawings")
		(19 "Cmts.User" user "User.Comments")
		(21 "Eco1.User" user "User.Eco1")
		(23 "Eco2.User" user "User.Eco2")
		(25 "Edge.Cuts" user "Board Geometry/Outline")
		(27 "Margin" user)
		(31 "F.CrtYd" user "Package Geometry/Place Bound Top")
		(29 "B.CrtYd" user "Package Geometry/Place Bound Bottom")
		(35 "F.Fab" user "Ref Des/Assembly Top")
		(33 "B.Fab" user "Ref Des/Assembly Bottom")
	)
	(footprint ""
		(layer "F.Cu")
		(at 291.84981 -295.89984)
		(property "Reference" "PEX2"
			(at -3.35153 35.56762 0)
			(unlocked yes)
			(layer "F.SilkS")
			(effects
				(font
					(size 2.032 1.524)
					(thickness 0.1524)
				)
				(justify left)
			)
		)
		(property "Value" ""
			(at 0 0 0)
			(layer "F.Fab")
			(effects
				(font
					(size 1.27 1.27)
				)
			)
		)
		(duplicate_pad_numbers_are_jumpers no)
		(pad "AW28" smd circle
			(at 2.84988 13.299948)
			(size 0.4572 0.4572)
			(layers "F.Cu" "F.Mask" "F.Paste")
			(net "PEX2_MODE_SEL4")
		)
		(pad "AW29" smd circle
			(at 3.800094 13.299948)
			(size 0.4572 0.4572)
			(layers "F.Cu" "F.Mask" "F.Paste")
			(net "PEX2_MODE_SEL8")
		)
		(pad "AW30" smd circle
			(at 4.750054 13.299948)
			(size 0.4572 0.4572)
			(layers "F.Cu" "F.Mask" "F.Paste")
			(net "PEX2_DBG_MODE2")
		)
		(pad "AW31" smd circle
			(at 5.700014 13.299948)
			(size 0.4572 0.4572)
			(layers "F.Cu" "F.Mask" "F.Paste")
			(net "PEX2_MODE_SEL11")
		)
		(pad "AW32" smd circle
			(at 6.649974 13.299948)
			(size 0.4572 0.4572)
			(layers "F.Cu" "F.Mask" "F.Paste")
			(net "PEX2_MODE_SEL12")
		)
		(pad "AW33" smd circle
			(at 7.599934 13.299948)
			(size 0.4572 0.4572)
			(layers "F.Cu" "F.Mask" "F.Paste")
			(net "Net_5350")
		)
		(pad "AW34" smd circle
			(at 8.549894 13.299948)
			(size 0.4572 0.4572)
			(layers "F.Cu" "F.Mask" "F.Paste")
			(net "PEX2_DBG_MODE4")
		)
		(pad "AW35" smd circle
			(at 9.500108 13.299948)
			(size 0.4572 0.4572)
			(layers "F.Cu" "F.Mask" "F.Paste")
			(net "Net_5329")
		)
		(pad "AW36" smd circle
			(at 10.450068 13.299948)
			(size 0.4572 0.4572)
			(layers "F.Cu" "F.Mask" "F.Paste")
			(net "Net_5353")
		)
		(pad "AW37" smd circle
			(at 11.400028 13.299948)
			(size 0.4572 0.4572)
			(layers "F.Cu" "F.Mask" "F.Paste")
			(net "Net_5357")
		)
		(pad "AW38" smd circle
			(at 12.349988 13.299948)
			(size 0.4572 0.4572)
			(layers "F.Cu" "F.Mask" "F.Paste")
			(net "PEX2_MODE_SEL1")
		)
		(pad "AW39" smd circle
			(at 13.299948 13.299948)
			(size 0.4572 0.4572)
			(layers "F.Cu" "F.Mask" "F.Paste")
			(net "Net_5324")
		)
		(pad "AW40" smd circle
			(at 14.249908 13.299948)
			(size 0.4572 0.4572)
			(layers "F.Cu" "F.Mask" "F.Paste")
			(net "GND")
		)
		(pad "AW41" smd circle
			(at 15.200122 13.299948)
			(size 0.4572 0.4572)
			(layers "F.Cu" "F.Mask" "F.Paste")
			(net "GND")
		)
		(pad "AW42" smd circle
			(at 16.150082 13.299948)
			(size 0.4572 0.4572)
			(layers "F.Cu" "F.Mask" "F.Paste")
			(net "GND")
		)
		(pad "AW43" smd circle
			(at 17.100042 13.299948)
			(size 0.4572 0.4572)
			(layers "F.Cu" "F.Mask" "F.Paste")
			(net "P5E_PEX2_STN0_TX_DP<6>")
		)
		(pad "AW44" smd circle
			(at 18.050002 13.299948)
			(size 0.4572 0.4572)
			(layers "F.Cu" "F.Mask" "F.Paste")
			(net "P5E_PEX2_STN0_TX_DN<6>")
		)
		(pad "AW45" smd circle
			(at 18.999962 13.299948)
			(size 0.4572 0.4572)
			(layers "F.Cu" "F.Mask" "F.Paste")
			(net "GND")
		)
		(pad "AW46" smd circle
			(at 19.949922 13.299948)
			(size 0.4572 0.4572)
			(layers "F.Cu" "F.Mask" "F.Paste")
			(net "P5E_PEX2_STN0_RX_DP<6>")
		)
		(pad "AW47" smd circle
			(at 20.899882 13.299948)
			(size 0.4572 0.4572)
			(layers "F.Cu" "F.Mask" "F.Paste")
			(net "P5E_PEX2_STN0_RX_DN<6>")
		)
		(pad "AW48" smd circle
			(at 21.850096 13.299948)
			(size 0.4572 0.4572)
			(layers "F.Cu" "F.Mask" "F.Paste")
			(net "GND")
		)
		(pad "AW49" smd circle
			(at 22.800056 13.299948)
			(size 0.4572 0.4572)
			(layers "F.Cu" "F.Mask" "F.Paste")
			(net "GND")
		)
		(pad "AY1" smd circle
			(at -22.800056 14.249908)
			(size 0.4572 0.4572)
			(layers "F.Cu" "F.Mask" "F.Paste")
			(net "Net_1600")
		)
		(pad "AY2" smd circle
			(at -21.850096 14.249908)
			(size 0.4572 0.4572)
			(layers "F.Cu" "F.Mask" "F.Paste")
			(net "Net_1588")
		)
		(pad "AY3" smd circle
			(at -20.899882 14.249908)
			(size 0.4572 0.4572)
			(layers "F.Cu" "F.Mask" "F.Paste")
			(net "GND")
		)
		(pad "AY4" smd circle
			(at -19.949922 14.249908)
			(size 0.4572 0.4572)
			(layers "F.Cu" "F.Mask" "F.Paste")
			(net "GND")
		)
		(pad "AY5" smd circle
			(at -18.999962 14.249908)
			(size 0.4572 0.4572)
			(layers "F.Cu" "F.Mask" "F.Paste")
			(net "GND")
		)
		(pad "AY6" smd circle
			(at -18.050002 14.249908)
			(size 0.4572 0.4572)
			(layers "F.Cu" "F.Mask" "F.Paste")
			(net "GND")
		)
		(pad "AY7" smd circle
			(at -17.100042 14.249908)
			(size 0.4572 0.4572)
			(layers "F.Cu" "F.Mask" "F.Paste")
			(net "GND")
		)
		(pad "AY8" smd circle
			(at -16.150082 14.249908)
			(size 0.4572 0.4572)
			(layers "F.Cu" "F.Mask" "F.Paste")
			(net "GND")
		)
		(pad "AY9" smd circle
			(at -15.200122 14.249908)
			(size 0.4572 0.4572)
			(layers "F.Cu" "F.Mask" "F.Paste")
			(net "GND")
		)
		(pad "AY10" smd circle
			(at -14.249908 14.249908)
			(size 0.4572 0.4572)
			(layers "F.Cu" "F.Mask" "F.Paste")
			(net "GND")
		)
		(pad "AY11" smd circle
			(at -13.299948 14.249908)
			(size 0.4572 0.4572)
			(layers "F.Cu" "F.Mask" "F.Paste")
			(net "GND")
		)
		(pad "AY12" smd circle
			(at -12.349988 14.249908)
			(size 0.4572 0.4572)
			(layers "F.Cu" "F.Mask" "F.Paste")
			(net "GND")
		)
		(pad "AY13" smd circle
			(at -11.400028 14.249908)
			(size 0.4572 0.4572)
			(layers "F.Cu" "F.Mask" "F.Paste")
			(net "GND")
		)
		(pad "AY14" smd circle
			(at -10.450068 14.249908)
			(size 0.4572 0.4572)
			(layers "F.Cu" "F.Mask" "F.Paste")
			(net "GND")
		)
		(pad "AY15" smd circle
			(at -9.500108 14.249908)
			(size 0.4572 0.4572)
			(layers "F.Cu" "F.Mask" "F.Paste")
			(net "GND")
		)
		(pad "AY16" smd circle
			(at -8.549894 14.249908)
			(size 0.4572 0.4572)
			(layers "F.Cu" "F.Mask" "F.Paste")
			(net "GND")
		)
		(pad "AY17" smd circle
			(at -7.599934 14.249908)
			(size 0.4572 0.4572)
			(layers "F.Cu" "F.Mask" "F.Paste")
			(net "GND")
		)
		(pad "AY18" smd circle
			(at -6.649974 14.249908)
			(size 0.4572 0.4572)
			(layers "F.Cu" "F.Mask" "F.Paste")
			(net "GND")
		)
		(pad "AY19" smd circle
			(at -5.700014 14.249908)
			(size 0.4572 0.4572)
			(layers "F.Cu" "F.Mask" "F.Paste")
			(net "GND")
		)
		(pad "AY20" smd circle
			(at -4.750054 14.249908)
			(size 0.4572 0.4572)
			(layers "F.Cu" "F.Mask" "F.Paste")
			(net "GND")
		)
		(pad "AY21" smd circle
			(at -3.800094 14.249908)
			(size 0.4572 0.4572)
			(layers "F.Cu" "F.Mask" "F.Paste")
			(net "GND")
		)
		(pad "AY22" smd circle
			(at -2.84988 14.249908)
			(size 0.4572 0.4572)
			(layers "F.Cu" "F.Mask" "F.Paste")
			(net "GND")
		)
		(pad "AY23" smd circle
			(at -1.89992 14.249908)
			(size 0.4572 0.4572)
			(layers "F.Cu" "F.Mask" "F.Paste")
			(net "GND")
		)
		(pad "AY24" smd circle
			(at -0.94996 14.249908)
			(size 0.4572 0.4572)
			(layers "F.Cu" "F.Mask" "F.Paste")
			(net "GND")
		)
		(pad "AY25" smd circle
			(at 0 14.249908)
			(size 0.4572 0.4572)
			(layers "F.Cu" "F.Mask" "F.Paste")
			(net "GND")
		)
		(pad "AY26" smd circle
			(at 0.94996 14.249908)
			(size 0.4572 0.4572)
			(layers "F.Cu" "F.Mask" "F.Paste")
			(net "GND")
		)
		(pad "AY27" smd circle
			(at 1.89992 14.249908)
			(size 0.4572 0.4572)
			(layers "F.Cu" "F.Mask" "F.Paste")
			(net "GND")
		)
		(pad "AY28" smd circle
			(at 2.84988 14.249908)
			(size 0.4572 0.4572)
			(layers "F.Cu" "F.Mask" "F.Paste")
			(net "GND")
		)
		(pad "AY29" smd circle
			(at 3.800094 14.249908)
			(size 0.4572 0.4572)
			(layers "F.Cu" "F.Mask" "F.Paste")
			(net "GND")
		)
		(pad "AY30" smd circle
			(at 4.750054 14.249908)
			(size 0.4572 0.4572)
			(layers "F.Cu" "F.Mask" "F.Paste")
			(net "GND")
		)
		(pad "AY31" smd circle
			(at 5.700014 14.249908)
			(size 0.4572 0.4572)
			(layers "F.Cu" "F.Mask" "F.Paste")
			(net "GND")
		)
		(pad "AY32" smd circle
			(at 6.649974 14.249908)
			(size 0.4572 0.4572)
			(layers "F.Cu" "F.Mask" "F.Paste")
			(net "GND")
		)
		(pad "AY33" smd circle
			(at 7.599934 14.249908)
			(size 0.4572 0.4572)
			(layers "F.Cu" "F.Mask" "F.Paste")
			(net "GND")
		)
		(pad "AY34" smd circle
			(at 8.549894 14.249908)
			(size 0.4572 0.4572)
			(layers "F.Cu" "F.Mask" "F.Paste")
			(net "GND")
		)
		(pad "AY35" smd circle
			(at 9.500108 14.249908)
			(size 0.4572 0.4572)
			(layers "F.Cu" "F.Mask" "F.Paste")
			(net "GND")
		)
		(pad "AY36" smd circle
			(at 10.450068 14.249908)
			(size 0.4572 0.4572)
			(layers "F.Cu" "F.Mask" "F.Paste")
			(net "GND")
		)
		(pad "AY37" smd circle
			(at 11.400028 14.249908)
			(size 0.4572 0.4572)
			(layers "F.Cu" "F.Mask" "F.Paste")
			(net "GND")
		)
		(pad "AY38" smd circle
			(at 12.349988 14.249908)
			(size 0.4572 0.4572)
			(layers "F.Cu" "F.Mask" "F.Paste")
			(net "GND")
		)
		(pad "AY39" smd circle
			(at 13.299948 14.249908)
			(size 0.4572 0.4572)
			(layers "F.Cu" "F.Mask" "F.Paste")
			(net "GND")
		)
		(pad "AY40" smd circle
			(at 14.249908 14.249908)
			(size 0.4572 0.4572)
			(layers "F.Cu" "F.Mask" "F.Paste")
			(net "GND")
		)
		(pad "AY41" smd circle
			(at 15.200122 14.249908)
			(size 0.4572 0.4572)
			(layers "F.Cu" "F.Mask" "F.Paste")
			(net "GND")
		)
		(pad "AY42" smd circle
			(at 16.150082 14.249908)
			(size 0.4572 0.4572)
			(layers "F.Cu" "F.Mask" "F.Paste")
			(net "GND")
		)
		(pad "AY43" smd circle
			(at 17.100042 14.249908)
			(size 0.4572 0.4572)
			(layers "F.Cu" "F.Mask" "F.Paste")
			(net "GND")
		)
		(pad "AY44" smd circle
			(at 18.050002 14.249908)
			(size 0.4572 0.4572)
			(layers "F.Cu" "F.Mask" "F.Paste")
			(net "GND")
		)
		(pad "AY45" smd circle
			(at 18.999962 14.249908)
			(size 0.4572 0.4572)
			(layers "F.Cu" "F.Mask" "F.Paste")
			(net "GND")
		)
		(pad "AY46" smd circle
			(at 19.949922 14.249908)
			(size 0.4572 0.4572)
			(layers "F.Cu" "F.Mask" "F.Paste")
			(net "GND")
		)
		(pad "AY47" smd circle
			(at 20.899882 14.249908)
			(size 0.4572 0.4572)
			(layers "F.Cu" "F.Mask" "F.Paste")
			(net "GND")
		)
		(pad "AY48" smd circle
			(at 21.850096 14.249908)
			(size 0.4572 0.4572)
			(layers "F.Cu" "F.Mask" "F.Paste")
			(net "P5E_PEX2_STN0_RX_DP<7>")
		)
		(pad "AY49" smd circle
			(at 22.800056 14.249908)
			(size 0.4572 0.4572)
			(layers "F.Cu" "F.Mask" "F.Paste")
			(net "P5E_PEX2_STN0_RX_DN<7>")
		)
		(pad "B1" smd circle
			(at -22.800056 -21.850096)
			(size 0.4572 0.4572)
			(layers "F.Cu" "F.Mask" "F.Paste")
			(net "GND")
		)
		(pad "B2" smd circle
			(at -21.850096 -21.850096)
			(size 0.4572 0.4572)
			(layers "F.Cu" "F.Mask" "F.Paste")
			(net "GND")
		)
		(pad "B3" smd circle
			(at -20.899882 -21.850096)
			(size 0.4572 0.4572)
			(layers "F.Cu" "F.Mask" "F.Paste")
			(net "P5E_PEX2_STN7_RX_DP<123>")
		)
		(pad "B4" smd circle
			(at -19.949922 -21.850096)
			(size 0.4572 0.4572)
			(layers "F.Cu" "F.Mask" "F.Paste")
			(net "GND")
		)
		(pad "B5" smd circle
			(at -18.999962 -21.850096)
			(size 0.4572 0.4572)
			(layers "F.Cu" "F.Mask" "F.Paste")
			(net "P5E_PEX2_STN7_RX_DP<125>")
		)
		(pad "B6" smd circle
			(at -18.050002 -21.850096)
			(size 0.4572 0.4572)
			(layers "F.Cu" "F.Mask" "F.Paste")
			(net "GND")
		)
		(pad "B7" smd circle
			(at -17.100042 -21.850096)
			(size 0.4572 0.4572)
			(layers "F.Cu" "F.Mask" "F.Paste")
			(net "P5E_PEX2_STN7_RX_DP<127>")
		)
		(pad "B8" smd circle
			(at -16.150082 -21.850096)
			(size 0.4572 0.4572)
			(layers "F.Cu" "F.Mask" "F.Paste")
			(net "GND")
		)
		(pad "B9" smd circle
			(at -15.200122 -21.850096)
			(size 0.4572 0.4572)
			(layers "F.Cu" "F.Mask" "F.Paste")
			(net "P5E_PEX2_STN6_RX_DP<110>")
		)
		(pad "B10" smd circle
			(at -14.249908 -21.850096)
			(size 0.4572 0.4572)
			(layers "F.Cu" "F.Mask" "F.Paste")
			(net "GND")
		)
		(pad "B11" smd circle
			(at -13.299948 -21.850096)
			(size 0.4572 0.4572)
			(layers "F.Cu" "F.Mask" "F.Paste")
			(net "P5E_PEX2_STN6_RX_DP<108>")
		)
		(pad "B12" smd circle
			(at -12.349988 -21.850096)
			(size 0.4572 0.4572)
			(layers "F.Cu" "F.Mask" "F.Paste")
			(net "GND")
		)
		(pad "B13" smd circle
			(at -11.400028 -21.850096)
			(size 0.4572 0.4572)
			(layers "F.Cu" "F.Mask" "F.Paste")
			(net "P5E_PEX2_STN6_RX_DP<106>")
		)
		(pad "B14" smd circle
			(at -10.450068 -21.850096)
			(size 0.4572 0.4572)
			(layers "F.Cu" "F.Mask" "F.Paste")
			(net "GND")
		)
		(pad "B15" smd circle
			(at -9.500108 -21.850096)
			(size 0.4572 0.4572)
			(layers "F.Cu" "F.Mask" "F.Paste")
			(net "P5E_PEX2_STN6_RX_DP<104>")
		)
		(pad "B16" smd circle
			(at -8.549894 -21.850096)
			(size 0.4572 0.4572)
			(layers "F.Cu" "F.Mask" "F.Paste")
			(net "GND")
		)
		(pad "B17" smd circle
			(at -7.599934 -21.850096)
			(size 0.4572 0.4572)
			(layers "F.Cu" "F.Mask" "F.Paste")
			(net "P5E_PEX2_STN6_RX_DP<102>")
		)
		(pad "B18" smd circle
			(at -6.649974 -21.850096)
			(size 0.4572 0.4572)
			(layers "F.Cu" "F.Mask" "F.Paste")
			(net "GND")
		)
		(pad "B19" smd circle
			(at -5.700014 -21.850096)
			(size 0.4572 0.4572)
			(layers "F.Cu" "F.Mask" "F.Paste")
			(net "P5E_PEX2_STN6_RX_DP<100>")
		)
		(pad "B20" smd circle
			(at -4.750054 -21.850096)
			(size 0.4572 0.4572)
			(layers "F.Cu" "F.Mask" "F.Paste")
			(net "GND")
		)
		(pad "B21" smd circle
			(at -3.800094 -21.850096)
			(size 0.4572 0.4572)
			(layers "F.Cu" "F.Mask" "F.Paste")
			(net "P5E_PEX2_STN6_RX_DP<98>")
		)
		(pad "B22" smd circle
			(at -2.84988 -21.850096)
			(size 0.4572 0.4572)
			(layers "F.Cu" "F.Mask" "F.Paste")
			(net "GND")
		)
		(pad "B23" smd circle
			(at -1.89992 -21.850096)
			(size 0.4572 0.4572)
			(layers "F.Cu" "F.Mask" "F.Paste")
			(net "P5E_PEX2_STN6_RX_DP<96>")
		)
		(pad "B24" smd circle
			(at -0.94996 -21.850096)
			(size 0.4572 0.4572)
			(layers "F.Cu" "F.Mask" "F.Paste")
			(net "GND")
		)
		(pad "B25" smd circle
			(at 0 -21.850096)
			(size 0.4572 0.4572)
			(layers "F.Cu" "F.Mask" "F.Paste")
			(net "P5E_PEX2_STN5_RX_DP<81>")
		)
		(pad "B26" smd circle
			(at 0.94996 -21.850096)
			(size 0.4572 0.4572)
			(layers "F.Cu" "F.Mask" "F.Paste")
			(net "GND")
		)
		(pad "B27" smd circle
			(at 1.89992 -21.850096)
			(size 0.4572 0.4572)
			(layers "F.Cu" "F.Mask" "F.Paste")
			(net "P5E_PEX2_STN5_RX_DP<83>")
		)
		(pad "B28" smd circle
			(at 2.84988 -21.850096)
			(size 0.4572 0.4572)
			(layers "F.Cu" "F.Mask" "F.Paste")
			(net "GND")
		)
		(pad "B29" smd circle
			(at 3.800094 -21.850096)
			(size 0.4572 0.4572)
			(layers "F.Cu" "F.Mask" "F.Paste")
			(net "P5E_PEX2_STN5_RX_DP<85>")
		)
		(pad "B30" smd circle
			(at 4.750054 -21.850096)
			(size 0.4572 0.4572)
			(layers "F.Cu" "F.Mask" "F.Paste")
			(net "GND")
		)
		(pad "B31" smd circle
			(at 5.700014 -21.850096)
			(size 0.4572 0.4572)
			(layers "F.Cu" "F.Mask" "F.Paste")
			(net "P5E_PEX2_STN5_RX_DP<87>")
		)
		(pad "B32" smd circle
			(at 6.649974 -21.850096)
			(size 0.4572 0.4572)
			(layers "F.Cu" "F.Mask" "F.Paste")
			(net "GND")
		)
		(pad "B33" smd circle
			(at 7.599934 -21.850096)
			(size 0.4572 0.4572)
			(layers "F.Cu" "F.Mask" "F.Paste")
			(net "P5E_PEX2_STN5_RX_DP<89>")
		)
		(pad "B34" smd circle
			(at 8.549894 -21.850096)
			(size 0.4572 0.4572)
			(layers "F.Cu" "F.Mask" "F.Paste")
			(net "GND")
		)
		(pad "B35" smd circle
			(at 9.500108 -21.850096)
			(size 0.4572 0.4572)
			(layers "F.Cu" "F.Mask" "F.Paste")
			(net "P5E_PEX2_STN5_RX_DP<91>")
		)
		(pad "B36" smd circle
			(at 10.450068 -21.850096)
			(size 0.4572 0.4572)
			(layers "F.Cu" "F.Mask" "F.Paste")
			(net "GND")
		)
		(pad "B37" smd circle
			(at 11.400028 -21.850096)
			(size 0.4572 0.4572)
			(layers "F.Cu" "F.Mask" "F.Paste")
			(net "P5E_PEX2_STN5_RX_DP<93>")
		)
		(pad "B38" smd circle
			(at 12.349988 -21.850096)
			(size 0.4572 0.4572)
			(layers "F.Cu" "F.Mask" "F.Paste")
			(net "GND")
		)
		(pad "B39" smd circle
			(at 13.299948 -21.850096)
			(size 0.4572 0.4572)
			(layers "F.Cu" "F.Mask" "F.Paste")
			(net "P5E_PEX2_STN5_RX_DP<95>")
		)
		(pad "B40" smd circle
			(at 14.249908 -21.850096)
			(size 0.4572 0.4572)
			(layers "F.Cu" "F.Mask" "F.Paste")
			(net "GND")
		)
		(pad "B41" smd circle
			(at 15.200122 -21.850096)
			(size 0.4572 0.4572)
			(layers "F.Cu" "F.Mask" "F.Paste")
			(net "P5E_PEX2_STN4_RX_DP<78>")
		)
		(pad "B42" smd circle
			(at 16.150082 -21.850096)
			(size 0.4572 0.4572)
			(layers "F.Cu" "F.Mask" "F.Paste")
			(net "GND")
		)
		(pad "B43" smd circle
			(at 17.100042 -21.850096)
			(size 0.4572 0.4572)
			(layers "F.Cu" "F.Mask" "F.Paste")
			(net "P5E_PEX2_STN4_RX_DP<76>")
		)
		(pad "B44" smd circle
			(at 18.050002 -21.850096)
			(size 0.4572 0.4572)
			(layers "F.Cu" "F.Mask" "F.Paste")
			(net "GND")
		)
		(pad "B45" smd circle
			(at 18.999962 -21.850096)
			(size 0.4572 0.4572)
			(layers "F.Cu" "F.Mask" "F.Paste")
			(net "P5E_PEX2_STN4_RX_DP<74>")
		)
		(pad "B46" smd circle
			(at 19.949922 -21.850096)
			(size 0.4572 0.4572)
			(layers "F.Cu" "F.Mask" "F.Paste")
			(net "GND")
		)
		(pad "B47" smd circle
			(at 20.899882 -21.850096)
			(size 0.4572 0.4572)
			(layers "F.Cu" "F.Mask" "F.Paste")
			(net "P5E_PEX2_STN4_RX_DP<72>")
		)
	)
)
